# S9S_MB_2U (Grand Teton) — schematic netlist excerpt (pin names and nets, part order shuffled) for the footprints in the layout excerpt that follows; sources: Cadence DE-HDL packaged netlist, KiCad conversion of 03242023_DA0F0TMBIJ0_F0T_Motherboard_J_brd_V01_OCP.brd

R3907  Q_RES  33K 1% CHIP  pkg 0402LF  page 301 : A = PDB_PRSNT_N ; B = GND
C1029  Q_CAP  22UF 4V 20% X6S  pkg C0402  page 74 : A = PVCCIN_CPU0 ; B = GND

(kicad_pcb
	(version 20260206)
	(generator "pcbnew")
	(generator_version "10.0")
	(general
		(thickness 1.6)
		(legacy_teardrops no)
	)
	(paper "A4")
	(title_block
		(title "03242023_DA0F0TMBIJ0_F0T_Motherboard_J_brd_V01_OCP.brd")
		(comment 1 "Grand Teton / footprints 3361-3362 of 6105")
	)
	(layers
		(0 "F.Cu" signal "TOP")
		(4 "In1.Cu" signal "GND")
		(6 "In2.Cu" signal "IN1")
		(8 "In3.Cu" signal "GND1")
		(10 "In4.Cu" signal "IN2")
		(12 "In5.Cu" signal "GND2")
		(14 "In6.Cu" signal "IN3")
		(16 "In7.Cu" signal "GND3")
		(18 "In8.Cu" signal "VCC")
		(20 "In9.Cu" signal "VCC1")
		(22 "In10.Cu" signal "GND4")
		(24 "In11.Cu" signal "IN4")
		(26 "In12.Cu" signal "GND5")
		(28 "In13.Cu" signal "IN5")
		(30 "In14.Cu" signal "GND6")
		(32 "In15.Cu" signal "IN6")
		(34 "In16.Cu" signal "GND7")
		(2 "B.Cu" signal "BOTTOM")
		(9 "F.Adhes" user "F.Adhesive")
		(11 "B.Adhes" user "B.Adhesive")
		(13 "F.Paste" user "Package Geometry/Pastemask Top")
		(15 "B.Paste" user "Package Geometry/Pastemask Bottom")
		(5 "F.SilkS" user "Ref Des/Silkscreen Top")
		(7 "B.SilkS" user "Ref Des/Silkscreen Bottom")
		(1 "F.Mask" user "Board Geometry/Soldermask Top")
		(3 "B.Mask" user "Board Geometry/Soldermask Bottom")
		(17 "Dwgs.User" user "User.Drawings")
		(19 "Cmts.User" user "User.Comments")
		(21 "Eco1.User" user "User.Eco1")
		(23 "Eco2.User" user "User.Eco2")
		(25 "Edge.Cuts" user "Board Geometry/Outline")
		(27 "Margin" user)
		(31 "F.CrtYd" user "Package Geometry/Place Bound Top")
		(29 "B.CrtYd" user "Package Geometry/Place Bound Bottom")
		(35 "F.Fab" user "Ref Des/Assembly Top")
		(33 "B.Fab" user "Ref Des/Assembly Bottom")
	)
	(footprint ""
		(layer "F.Cu")
		(at 189.65037 -426.303948 180)
		(property "Reference" "R3907"
			(at 0 0 180)
			(layer "F.SilkS")
			(hide yes)
			(effects
				(font
					(size 1.27 1.27)
				)
			)
		)
		(property "Value" ""
			(at 0 0 180)
			(layer "F.Fab")
			(effects
				(font
					(size 1.27 1.27)
				)
			)
		)
		(duplicate_pad_numbers_are_jumpers no)
		(fp_line
			(start 0.7874 0.4064)
			(end -0.7874 0.4064)
			(stroke
				(width 0.1524)
				(type default)
			)
			(layer "F.SilkS")
		)
		(fp_line
			(start 0.7874 -0.4064)
			(end 0.7874 0.4064)
			(stroke
				(width 0.1524)
				(type default)
			)
			(layer "F.SilkS")
		)
		(fp_line
			(start -0.7874 0.4064)
			(end -0.7874 -0.4064)
			(stroke
				(width 0.1524)
				(type default)
			)
			(layer "F.SilkS")
		)
		(fp_line
			(start -0.7874 -0.4064)
			(end 0.7874 -0.4064)
			(stroke
				(width 0.1524)
				(type default)
			)
			(layer "F.SilkS")
		)
		(fp_line
			(start 0.67945 0.3048)
			(end 0.120396 0.3048)
			(stroke
				(width 0.1)
				(type default)
			)
			(layer "F.Fab")
		)
		(fp_line
			(start 0.67945 -0.3048)
			(end 0.67945 0.3048)
			(stroke
				(width 0.1)
				(type default)
			)
			(layer "F.Fab")
		)
		(fp_line
			(start 0.12065 -0.2794)
			(end 0.12065 -0.3048)
			(stroke
				(width 0.1)
				(type default)
			)
			(layer "F.Fab")
		)
		(fp_line
			(start 0.12065 -0.3048)
			(end 0.67945 -0.3048)
			(stroke
				(width 0.1)
				(type default)
			)
			(layer "F.Fab")
		)
		(fp_line
			(start 0.120396 0.3048)
			(end 0.120396 0.2794)
			(stroke
				(width 0.1)
				(type default)
			)
			(layer "F.Fab")
		)
		(fp_line
			(start 0.120396 0.2794)
			(end -0.12065 0.2794)
			(stroke
				(width 0.1)
				(type default)
			)
			(layer "F.Fab")
		)
		(fp_line
			(start -0.12065 0.3048)
			(end -0.67945 0.3048)
			(stroke
				(width 0.1)
				(type default)
			)
			(layer "F.Fab")
		)
		(fp_line
			(start -0.12065 0.2794)
			(end -0.12065 0.3048)
			(stroke
				(width 0.1)
				(type default)
			)
			(layer "F.Fab")
		)
		(fp_line
			(start -0.12065 -0.2794)
			(end 0.12065 -0.2794)
			(stroke
				(width 0.1)
				(type default)
			)
			(layer "F.Fab")
		)
		(fp_line
			(start -0.12065 -0.305054)
			(end -0.12065 -0.2794)
			(stroke
				(width 0.1)
				(type default)
			)
			(layer "F.Fab")
		)
		(fp_line
			(start -0.67945 0.3048)
			(end -0.67945 -0.305054)
			(stroke
				(width 0.1)
				(type default)
			)
			(layer "F.Fab")
		)
		(fp_line
			(start -0.67945 -0.305054)
			(end -0.12065 -0.305054)
			(stroke
				(width 0.1)
				(type default)
			)
			(layer "F.Fab")
		)
		(pad "1" smd circle
			(at -0.40005 0 180)
			(size 0 0)
			(layers "F.Cu" "F.Mask" "F.Paste")
			(net "PDB_PRSNT_N")
		)
		(pad "2" smd circle
			(at 0.40005 0 180)
			(size 0 0)
			(layers "F.Cu" "F.Mask" "F.Paste")
			(net "GND")
		)
	)
	(footprint ""
		(layer "F.Cu")
		(at 365.46663 -241.976656 -90)
		(property "Reference" "C1029"
			(at 0 0 270)
			(layer "F.SilkS")
			(hide yes)
			(effects
				(font
					(size 1.27 1.27)
				)
			)
		)
		(property "Value" ""
			(at 0 0 270)
			(layer "F.Fab")
			(effects
				(font
					(size 1.27 1.27)
				)
			)
		)
		(duplicate_pad_numbers_are_jumpers no)
		(fp_line
			(start -0.7874 0.4064)
			(end -0.7874 -0.4064)
			(stroke
				(width 0.1524)
				(type default)
			)
			(layer "F.SilkS")
		)
		(fp_line
			(start 0.7874 0.4064)
			(end -0.7874 0.4064)
			(stroke
				(width 0.1524)
				(type default)
			)
			(layer "F.SilkS")
		)
		(fp_line
			(start -0.7874 -0.4064)
			(end 0.7874 -0.4064)
			(stroke
				(width 0.1524)
				(type default)
			)
			(layer "F.SilkS")
		)
		(fp_line
			(start 0.7874 -0.4064)
			(end 0.7874 0.4064)
			(stroke
				(width 0.1524)
				(type default)
			)
			(layer "F.SilkS")
		)
		(fp_line
			(start -0.67945 0.3048)
			(end -0.67945 -0.305054)
			(stroke
				(width 0.1)
				(type default)
			)
			(layer "F.Fab")
		)
		(fp_line
			(start -0.12065 0.3048)
			(end -0.67945 0.3048)
			(stroke
				(width 0.1)
				(type default)
			)
			(layer "F.Fab")
		)
		(fp_line
			(start 0.120396 0.3048)
			(end 0.120396 0.2794)
			(stroke
				(width 0.1)
				(type default)
			)
			(layer "F.Fab")
		)
		(fp_line
			(start 0.67945 0.3048)
			(end 0.120396 0.3048)
			(stroke
				(width 0.1)
				(type default)
			)
			(layer "F.Fab")
		)
		(fp_line
			(start -0.12065 0.2794)
			(end -0.12065 0.3048)
			(stroke
				(width 0.1)
				(type default)
			)
			(layer "F.Fab")
		)
		(fp_line
			(start 0.120396 0.2794)
			(end -0.12065 0.2794)
			(stroke
				(width 0.1)
				(type default)
			)
			(layer "F.Fab")
		)
		(fp_line
			(start -0.12065 -0.2794)
			(end 0.12065 -0.2794)
			(stroke
				(width 0.1)
				(type default)
			)
			(layer "F.Fab")
		)
		(fp_line
			(start 0.12065 -0.2794)
			(end 0.12065 -0.3048)
			(stroke
				(width 0.1)
				(type default)
			)
			(layer "F.Fab")
		)
		(fp_line
			(start 0.12065 -0.3048)
			(end 0.67945 -0.3048)
			(stroke
				(width 0.1)
				(type default)
			)
			(layer "F.Fab")
		)
		(fp_line
			(start 0.67945 -0.3048)
			(end 0.67945 0.3048)
			(stroke
				(width 0.1)
				(type default)
			)
			(layer "F.Fab")
		)
		(fp_line
			(start -0.67945 -0.305054)
			(end -0.12065 -0.305054)
			(stroke
				(width 0.1)
				(type default)
			)
			(layer "F.Fab")
		)
		(fp_line
			(start -0.12065 -0.305054)
			(end -0.12065 -0.2794)
			(stroke
				(width 0.1)
				(type default)
			)
			(layer "F.Fab")
		)
		(pad "1" smd circle
			(at -0.40005 0 270)
			(size 0 0)
			(layers "F.Cu" "F.Mask" "F.Paste")
			(net "PVCCIN_CPU0")
		)
		(pad "2" smd circle
			(at 0.40005 0 270)
			(size 0 0)
			(layers "F.Cu" "F.Mask" "F.Paste")
			(net "GND")
		)
	)
)
